# BASEBOARD_FAB2 (Tioga Pass) — schematic netlist excerpt (pin names and nets, part order shuffled) for the footprints in the layout excerpt that follows; sources: Cadence DE-HDL packaged netlist, KiCad conversion of Wiwynn_Tioga_Pass_MB.brd

Q7E1  FET_N_DUAL  NTJD4001N FET  pkg SMLF  page 94
  SOURCE(0)  = GND
  GATE(0)  = IRQ_PVDDQ_DEF_VRHOT_LVT3_N
  DRAIN(0)  = H_CPU0_MEMDEF_MEMHOT_G_N
  SOURCE(0)  = GND
  GATE(0)  = H_CPU0_MEMDEF_MEMHOT
  DRAIN(0)  = H_CPU0_MEMDEF_MEMHOT

CT4  CAP  1000PF 50V 10% X7R  pkg 0402LF  page 202 : A = A_TSENSE_PVCCIN_CPU0 ; B = GND

(kicad_pcb
	(version 20260206)
	(generator "pcbnew")
	(generator_version "10.0")
	(general
		(thickness 1.6)
		(legacy_teardrops no)
	)
	(paper "A4")
	(title_block
		(title "Wiwynn_Tioga_Pass_MB.brd")
		(comment 1 "Tioga Pass / footprints 3091-3092 of 4770")
	)
	(layers
		(0 "F.Cu" signal "TOP")
		(4 "In1.Cu" signal "L2GND")
		(6 "In2.Cu" signal "L3")
		(8 "In3.Cu" signal "L4GND")
		(10 "In4.Cu" signal "L5")
		(12 "In5.Cu" signal "L6GND")
		(14 "In6.Cu" signal "L7VCC")
		(16 "In7.Cu" signal "L8VCC")
		(18 "In8.Cu" signal "L9GND")
		(20 "In9.Cu" signal "L10")
		(22 "In10.Cu" signal "L11GND")
		(24 "In11.Cu" signal "L12")
		(26 "In12.Cu" signal "L13GND")
		(2 "B.Cu" signal "BOTTOM")
		(9 "F.Adhes" user "F.Adhesive")
		(11 "B.Adhes" user "B.Adhesive")
		(13 "F.Paste" user "Package Geometry/Pastemask Top")
		(15 "B.Paste" user "Package Geometry/Pastemask Bottom")
		(5 "F.SilkS" user "Ref Des/Silkscreen Top")
		(7 "B.SilkS" user "Ref Des/Silkscreen Bottom")
		(1 "F.Mask" user "Board Geometry/Soldermask Top")
		(3 "B.Mask" user "Board Geometry/Soldermask Bottom")
		(17 "Dwgs.User" user "User.Drawings")
		(19 "Cmts.User" user "User.Comments")
		(21 "Eco1.User" user "User.Eco1")
		(23 "Eco2.User" user "User.Eco2")
		(25 "Edge.Cuts" user "Board Geometry/Outline")
		(27 "Margin" user)
		(31 "F.CrtYd" user "Package Geometry/Place Bound Top")
		(29 "B.CrtYd" user "Package Geometry/Place Bound Bottom")
		(35 "F.Fab" user "Ref Des/Assembly Top")
		(33 "B.Fab" user "Ref Des/Assembly Bottom")
	)
	(footprint ""
		(layer "B.Cu")
		(at 409.884118 -90.193114 180)
		(property "Reference" "Q7E1"
			(at -0.11938 -0.97663 180)
			(unlocked yes)
			(layer "B.SilkS")
			(effects
				(font
					(size 0.7874 0.5842)
					(thickness 0.1524)
				)
				(justify left mirror)
			)
		)
		(property "Value" ""
			(at 0 0 0)
			(layer "B.Fab")
			(effects
				(font
					(size 1.27 1.27)
				)
				(justify mirror)
			)
		)
		(duplicate_pad_numbers_are_jumpers no)
		(fp_circle
			(center 0.508 -0.7874)
			(end 0.381 -0.7874)
			(stroke
				(width 0.254)
				(type default)
			)
			(fill no)
			(layer "B.SilkS")
		)
		(fp_poly
			(pts
				(xy -0.2159 1.7526) (xy -1.5621 1.7526) (xy -1.5621 -0.4572) (xy -0.2159 -0.4572)
			)
			(stroke
				(width 0)
				(type default)
			)
			(fill no)
			(layer "B.CrtYd")
		)
		(fp_line
			(start -0.2159 1.75514)
			(end -1.5621 1.75514)
			(stroke
				(width 0.1)
				(type default)
			)
			(layer "B.Fab")
		)
		(fp_line
			(start -0.2159 -0.45466)
			(end -0.2159 1.75514)
			(stroke
				(width 0.1)
				(type default)
			)
			(layer "B.Fab")
		)
		(fp_line
			(start -1.5621 1.75514)
			(end -1.5621 -0.45466)
			(stroke
				(width 0.1)
				(type default)
			)
			(layer "B.Fab")
		)
		(fp_line
			(start -1.5621 -0.45466)
			(end -0.2159 -0.45466)
			(stroke
				(width 0.1)
				(type default)
			)
			(layer "B.Fab")
		)
		(fp_circle
			(center 0.508 -0.7874)
			(end 0.381 -0.7874)
			(stroke
				(width 0.254)
				(type default)
			)
			(fill no)
			(layer "B.Fab")
		)
		(pad "1" smd rect
			(at 0 0)
			(size 1.016 0.381)
			(layers "B.Cu" "B.Mask" "B.Paste")
			(net "GND")
		)
		(pad "2" smd rect
			(at 0 0.65024)
			(size 1.016 0.381)
			(layers "B.Cu" "B.Mask" "B.Paste")
			(net "IRQ_PVDDQ_DEF_VRHOT_LVT3_N")
		)
		(pad "3" smd rect
			(at 0 1.30048)
			(size 1.016 0.381)
			(layers "B.Cu" "B.Mask" "B.Paste")
			(net "H_CPU0_MEMDEF_MEMHOT_G_N")
		)
		(pad "4" smd rect
			(at -1.778 1.30048)
			(size 1.016 0.381)
			(layers "B.Cu" "B.Mask" "B.Paste")
			(net "GND")
		)
		(pad "5" smd rect
			(at -1.778 0.65024)
			(size 1.016 0.381)
			(layers "B.Cu" "B.Mask" "B.Paste")
			(net "H_CPU0_MEMDEF_MEMHOT")
		)
		(pad "6" smd rect
			(at -1.778 0)
			(size 1.016 0.381)
			(layers "B.Cu" "B.Mask" "B.Paste")
			(net "H_CPU0_MEMDEF_MEMHOT")
		)
		(zone
			(layer "B.Cu")
			(hatch none 0.5)
			(connect_pads
				(clearance 0)
			)
			(min_thickness 0.25)
			(keepout
				(tracks allowed)
				(vias not_allowed)
				(pads allowed)
				(copperpour not_allowed)
				(footprints allowed)
			)
			(placement
				(enabled no)
				(sheetname "")
			)
			(fill
				(thermal_gap 0.5)
				(thermal_bridge_width 0.5)
				(island_removal_mode 0)
			)
			(polygon
				(pts
					(xy 409.376118 -90.002614) (xy 410.392118 -90.002614) (xy 410.392118 -91.691714) (xy 409.376118 -91.691714)
				)
			)
		)
		(zone
			(layer "B.Cu")
			(hatch none 0.5)
			(connect_pads
				(clearance 0)
			)
			(min_thickness 0.25)
			(keepout
				(tracks allowed)
				(vias not_allowed)
				(pads allowed)
				(copperpour not_allowed)
				(footprints allowed)
			)
			(placement
				(enabled no)
				(sheetname "")
			)
			(fill
				(thermal_gap 0.5)
				(thermal_bridge_width 0.5)
				(island_removal_mode 0)
			)
			(polygon
				(pts
					(xy 411.154118 -90.002614) (xy 412.170118 -90.002614) (xy 412.170118 -91.691714) (xy 411.154118 -91.691714)
				)
			)
		)
	)
	(footprint ""
		(layer "B.Cu")
		(at 195.2752 -64.008 90)
		(property "Reference" "CT4"
			(at 0.8382 -0.84963 90)
			(unlocked yes)
			(layer "B.SilkS")
			(effects
				(font
					(size 0.7874 0.5842)
					(thickness 0.1524)
				)
				(justify left mirror)
			)
		)
		(property "Value" ""
			(at 0 0 90)
			(layer "B.Fab")
			(effects
				(font
					(size 1.27 1.27)
				)
				(justify mirror)
			)
		)
		(duplicate_pad_numbers_are_jumpers no)
		(fp_poly
			(pts
				(xy -0.3048 -0.1016) (xy -0.3048 0.9906) (xy 0.3048 0.9906) (xy 0.3048 -0.1016)
			)
			(stroke
				(width 0)
				(type default)
			)
			(fill no)
			(layer "B.CrtYd")
		)
		(fp_line
			(start 0.3048 -0.1016)
			(end 0.3048 0.9906)
			(stroke
				(width 0.1)
				(type default)
			)
			(layer "B.Fab")
		)
		(fp_line
			(start -0.3048 -0.1016)
			(end 0.3048 -0.1016)
			(stroke
				(width 0.1)
				(type default)
			)
			(layer "B.Fab")
		)
		(fp_line
			(start 0.3048 0.9906)
			(end -0.3048 0.9906)
			(stroke
				(width 0.1)
				(type default)
			)
			(layer "B.Fab")
		)
		(fp_line
			(start -0.3048 0.9906)
			(end -0.3048 -0.1016)
			(stroke
				(width 0.1)
				(type default)
			)
			(layer "B.Fab")
		)
		(pad "1" smd rect
			(at 0 0 270)
			(size 0.508 0.508)
			(layers "B.Cu" "B.Mask" "B.Paste")
			(net "A_TSENSE_PVCCIN_CPU0")
		)
		(pad "2" smd rect
			(at 0 0.889 270)
			(size 0.508 0.508)
			(layers "B.Cu" "B.Mask" "B.Paste")
			(net "GND")
		)
		(zone
			(layer "B.Cu")
			(hatch none 0.5)
			(connect_pads
				(clearance 0)
			)
			(min_thickness 0.25)
			(keepout
				(tracks allowed)
				(vias not_allowed)
				(pads allowed)
				(copperpour not_allowed)
				(footprints allowed)
			)
			(placement
				(enabled no)
				(sheetname "")
			)
			(fill
				(thermal_gap 0.5)
				(thermal_bridge_width 0.5)
				(island_removal_mode 0)
			)
			(polygon
				(pts
					(xy 195.5292 -64.262) (xy 195.5292 -63.754) (xy 195.9102 -63.754) (xy 195.9102 -64.262)
				)
			)
		)
		(zone
			(layer "B.Cu")
			(hatch none 0.5)
			(connect_pads
				(clearance 0)
			)
			(min_thickness 0.25)
			(keepout
				(tracks not_allowed)
				(vias allowed)
				(pads allowed)
				(copperpour not_allowed)
				(footprints allowed)
			)
			(placement
				(enabled no)
				(sheetname "")
			)
			(fill
				(thermal_gap 0.5)
				(thermal_bridge_width 0.5)
				(island_removal_mode 0)
			)
			(polygon
				(pts
					(xy 195.9102 -64.262) (xy 195.9102 -63.754) (xy 195.5292 -63.754) (xy 195.5292 -64.262)
				)
			)
		)
	)
)
